# T6G (Grand Teton) — schematic netlist excerpt (pin names and nets, part order shuffled) for the footprints in the layout excerpt that follows; sources: Cadence DE-HDL packaged netlist, KiCad conversion of 04192023_DAF0TMB3IC0_F0TG_MB_C_brd_V02_OCP.brd

R1340  Q_RES  0 5% CHIP  pkg 0402LF  page 82 : A = OCP_SFF_P3V3_P12V_ADC_ALERT ; B = OCP_SFF_P3V3_P12V_ADC_R_ALERT
C76  Q_CAP  10UF 6.3V 20% X6S  pkg C0402  page 182 : A = P3V3_9ZXL045_P0_VDDA ; B = GND

(kicad_pcb
	(version 20260206)
	(generator "pcbnew")
	(generator_version "10.0")
	(general
		(thickness 1.6)
		(legacy_teardrops no)
	)
	(paper "A4")
	(title_block
		(title "04192023_DAF0TMB3IC0_F0TG_MB_C_brd_V02_OCP.brd")
		(comment 1 "Grand Teton / footprints 343-344 of 8354")
	)
	(layers
		(0 "F.Cu" signal "TOP")
		(4 "In1.Cu" signal "GND")
		(6 "In2.Cu" signal "IN1")
		(8 "In3.Cu" signal "GND1")
		(10 "In4.Cu" signal "IN2")
		(12 "In5.Cu" signal "GND2")
		(14 "In6.Cu" signal "IN3")
		(16 "In7.Cu" signal "GND3")
		(18 "In8.Cu" signal "VCC")
		(20 "In9.Cu" signal "VCC1")
		(22 "In10.Cu" signal "GND4")
		(24 "In11.Cu" signal "IN4")
		(26 "In12.Cu" signal "GND5")
		(28 "In13.Cu" signal "IN5")
		(30 "In14.Cu" signal "GND6")
		(32 "In15.Cu" signal "IN6")
		(34 "In16.Cu" signal "GND7")
		(2 "B.Cu" signal "BOTTOM")
		(9 "F.Adhes" user "F.Adhesive")
		(11 "B.Adhes" user "B.Adhesive")
		(13 "F.Paste" user "Package Geometry/Pastemask Top")
		(15 "B.Paste" user "Package Geometry/Pastemask Bottom")
		(5 "F.SilkS" user "Ref Des/Silkscreen Top")
		(7 "B.SilkS" user "Ref Des/Silkscreen Bottom")
		(1 "F.Mask" user "Board Geometry/Soldermask Top")
		(3 "B.Mask" user "Board Geometry/Soldermask Bottom")
		(17 "Dwgs.User" user "User.Drawings")
		(19 "Cmts.User" user "User.Comments")
		(21 "Eco1.User" user "User.Eco1")
		(23 "Eco2.User" user "User.Eco2")
		(25 "Edge.Cuts" user "Board Geometry/Outline")
		(27 "Margin" user)
		(31 "F.CrtYd" user "Package Geometry/Place Bound Top")
		(29 "B.CrtYd" user "Package Geometry/Place Bound Bottom")
		(35 "F.Fab" user "Ref Des/Assembly Top")
		(33 "B.Fab" user "Ref Des/Assembly Bottom")
	)
	(footprint ""
		(layer "F.Cu")
		(at 284.556962 -426.19549 90)
		(property "Reference" "C76"
			(at 0 0 90)
			(layer "F.SilkS")
			(hide yes)
			(effects
				(font
					(size 1.27 1.27)
				)
			)
		)
		(property "Value" ""
			(at 0 0 90)
			(layer "F.Fab")
			(effects
				(font
					(size 1.27 1.27)
				)
			)
		)
		(duplicate_pad_numbers_are_jumpers no)
		(fp_line
			(start 0.7874 -0.4064)
			(end 0.7874 0.4064)
			(stroke
				(width 0.1524)
				(type default)
			)
			(layer "F.SilkS")
		)
		(fp_line
			(start -0.7874 -0.4064)
			(end 0.7874 -0.4064)
			(stroke
				(width 0.1524)
				(type default)
			)
			(layer "F.SilkS")
		)
		(fp_line
			(start 0.7874 0.4064)
			(end -0.7874 0.4064)
			(stroke
				(width 0.1524)
				(type default)
			)
			(layer "F.SilkS")
		)
		(fp_line
			(start -0.7874 0.4064)
			(end -0.7874 -0.4064)
			(stroke
				(width 0.1524)
				(type default)
			)
			(layer "F.SilkS")
		)
		(fp_line
			(start -0.12065 -0.305054)
			(end -0.12065 -0.2794)
			(stroke
				(width 0.1)
				(type default)
			)
			(layer "F.Fab")
		)
		(fp_line
			(start -0.67945 -0.305054)
			(end -0.12065 -0.305054)
			(stroke
				(width 0.1)
				(type default)
			)
			(layer "F.Fab")
		)
		(fp_line
			(start 0.67945 -0.3048)
			(end 0.67945 0.3048)
			(stroke
				(width 0.1)
				(type default)
			)
			(layer "F.Fab")
		)
		(fp_line
			(start 0.12065 -0.3048)
			(end 0.67945 -0.3048)
			(stroke
				(width 0.1)
				(type default)
			)
			(layer "F.Fab")
		)
		(fp_line
			(start 0.12065 -0.2794)
			(end 0.12065 -0.3048)
			(stroke
				(width 0.1)
				(type default)
			)
			(layer "F.Fab")
		)
		(fp_line
			(start -0.12065 -0.2794)
			(end 0.12065 -0.2794)
			(stroke
				(width 0.1)
				(type default)
			)
			(layer "F.Fab")
		)
		(fp_line
			(start 0.120396 0.2794)
			(end -0.12065 0.2794)
			(stroke
				(width 0.1)
				(type default)
			)
			(layer "F.Fab")
		)
		(fp_line
			(start -0.12065 0.2794)
			(end -0.12065 0.3048)
			(stroke
				(width 0.1)
				(type default)
			)
			(layer "F.Fab")
		)
		(fp_line
			(start 0.67945 0.3048)
			(end 0.120396 0.3048)
			(stroke
				(width 0.1)
				(type default)
			)
			(layer "F.Fab")
		)
		(fp_line
			(start 0.120396 0.3048)
			(end 0.120396 0.2794)
			(stroke
				(width 0.1)
				(type default)
			)
			(layer "F.Fab")
		)
		(fp_line
			(start -0.12065 0.3048)
			(end -0.67945 0.3048)
			(stroke
				(width 0.1)
				(type default)
			)
			(layer "F.Fab")
		)
		(fp_line
			(start -0.67945 0.3048)
			(end -0.67945 -0.305054)
			(stroke
				(width 0.1)
				(type default)
			)
			(layer "F.Fab")
		)
		(pad "1" smd circle
			(at -0.40005 0 90)
			(size 0 0)
			(layers "F.Cu" "F.Mask" "F.Paste")
			(net "P3V3_9ZXL045_P0_VDDA")
		)
		(pad "2" smd circle
			(at 0.40005 0 90)
			(size 0 0)
			(layers "F.Cu" "F.Mask" "F.Paste")
			(net "GND")
		)
	)
	(footprint ""
		(layer "F.Cu")
		(at 210.485482 -102.958138)
		(property "Reference" "R1340"
			(at 0 0 0)
			(layer "F.SilkS")
			(hide yes)
			(effects
				(font
					(size 1.27 1.27)
				)
			)
		)
		(property "Value" ""
			(at 0 0 0)
			(layer "F.Fab")
			(effects
				(font
					(size 1.27 1.27)
				)
			)
		)
		(duplicate_pad_numbers_are_jumpers no)
		(fp_line
			(start -0.7874 -0.4064)
			(end 0.7874 -0.4064)
			(stroke
				(width 0.1524)
				(type default)
			)
			(layer "F.SilkS")
		)
		(fp_line
			(start -0.7874 0.4064)
			(end -0.7874 -0.4064)
			(stroke
				(width 0.1524)
				(type default)
			)
			(layer "F.SilkS")
		)
		(fp_line
			(start 0.7874 -0.4064)
			(end 0.7874 0.4064)
			(stroke
				(width 0.1524)
				(type default)
			)
			(layer "F.SilkS")
		)
		(fp_line
			(start 0.7874 0.4064)
			(end -0.7874 0.4064)
			(stroke
				(width 0.1524)
				(type default)
			)
			(layer "F.SilkS")
		)
		(fp_line
			(start -0.67945 -0.305054)
			(end -0.12065 -0.305054)
			(stroke
				(width 0.1)
				(type default)
			)
			(layer "F.Fab")
		)
		(fp_line
			(start -0.67945 0.3048)
			(end -0.67945 -0.305054)
			(stroke
				(width 0.1)
				(type default)
			)
			(layer "F.Fab")
		)
		(fp_line
			(start -0.12065 -0.305054)
			(end -0.12065 -0.2794)
			(stroke
				(width 0.1)
				(type default)
			)
			(layer "F.Fab")
		)
		(fp_line
			(start -0.12065 -0.2794)
			(end 0.12065 -0.2794)
			(stroke
				(width 0.1)
				(type default)
			)
			(layer "F.Fab")
		)
		(fp_line
			(start -0.12065 0.2794)
			(end -0.12065 0.3048)
			(stroke
				(width 0.1)
				(type default)
			)
			(layer "F.Fab")
		)
		(fp_line
			(start -0.12065 0.3048)
			(end -0.67945 0.3048)
			(stroke
				(width 0.1)
				(type default)
			)
			(layer "F.Fab")
		)
		(fp_line
			(start 0.120396 0.2794)
			(end -0.12065 0.2794)
			(stroke
				(width 0.1)
				(type default)
			)
			(layer "F.Fab")
		)
		(fp_line
			(start 0.120396 0.3048)
			(end 0.120396 0.2794)
			(stroke
				(width 0.1)
				(type default)
			)
			(layer "F.Fab")
		)
		(fp_line
			(start 0.12065 -0.3048)
			(end 0.67945 -0.3048)
			(stroke
				(width 0.1)
				(type default)
			)
			(layer "F.Fab")
		)
		(fp_line
			(start 0.12065 -0.2794)
			(end 0.12065 -0.3048)
			(stroke
				(width 0.1)
				(type default)
			)
			(layer "F.Fab")
		)
		(fp_line
			(start 0.67945 -0.3048)
			(end 0.67945 0.3048)
			(stroke
				(width 0.1)
				(type default)
			)
			(layer "F.Fab")
		)
		(fp_line
			(start 0.67945 0.3048)
			(end 0.120396 0.3048)
			(stroke
				(width 0.1)
				(type default)
			)
			(layer "F.Fab")
		)
		(pad "1" smd circle
			(at -0.40005 0)
			(size 0 0)
			(layers "F.Cu" "F.Mask" "F.Paste")
			(net "OCP_SFF_P3V3_P12V_ADC_ALERT")
		)
		(pad "2" smd circle
			(at 0.40005 0)
			(size 0 0)
			(layers "F.Cu" "F.Mask" "F.Paste")
			(net "OCP_SFF_P3V3_P12V_ADC_R_ALERT")
		)
	)
)
